(kicad_pcb
	(version 20241229)
	(generator "pcbnew")
	(generator_version "9.0")
	(general
		(thickness 1.294)
		(legacy_teardrops no)
	)
	(paper "A3")
	(title_block
		(title "Kintex 410T devboard")
		(date "2024-04-03")
		(rev "1.1.2")
		(comment 9 "footprints 201-205 of 975")
	)
	(layers
		(0 "F.Cu" mixed)
		(4 "In1.Cu" power)
		(6 "In2.Cu" power)
		(8 "In3.Cu" mixed)
		(10 "In4.Cu" power)
		(12 "In5.Cu" mixed)
		(14 "In6.Cu" power)
		(16 "In7.Cu" mixed)
		(18 "In8.Cu" power)
		(2 "B.Cu" mixed)
		(9 "F.Adhes" user "F.Adhesive")
		(11 "B.Adhes" user "B.Adhesive")
		(13 "F.Paste" user)
		(15 "B.Paste" user)
		(5 "F.SilkS" user "F.Silkscreen")
		(7 "B.SilkS" user "B.Silkscreen")
		(1 "F.Mask" user)
		(3 "B.Mask" user)
		(17 "Dwgs.User" user "User.Drawings")
		(19 "Cmts.User" user "User.Comments")
		(21 "Eco1.User" user "User.Eco1")
		(23 "Eco2.User" user "User.Eco2")
		(25 "Edge.Cuts" user)
		(27 "Margin" user)
		(31 "F.CrtYd" user "F.Courtyard")
		(29 "B.CrtYd" user "B.Courtyard")
		(35 "F.Fab" user)
		(33 "B.Fab" user)
	)
	(footprint "antmicro-footprints:C_Pol_EIA-B"
		(layer "F.Cu")
		(at 201.061 149.4)
		(property "Reference" "C125"
			(at -1.401 -1.76 0)
			(layer "F.SilkS")
			(effects
				(font
					(size 0.7 0.7)
					(thickness 0.15)
				)
				(justify left bottom)
			)
		)
		(property "Value" "C_Pol_330u_6.3V_KEMET-T520-B"
			(at -2.34 2.45 0)
			(layer "F.Fab")
			(effects
				(font
					(size 0.7 0.7)
					(thickness 0.15)
				)
				(justify left bottom)
			)
		)
		(property "Description" "Tantalum Polymer Capacitor, KO-CAP®, 330 µF, ± 20%, 6.3 V, B, 0.04 ohm, 1411 [3528 Metric]"
			(at 0 0 0)
			(layer "F.Fab")
			(hide yes)
			(effects
				(font
					(size 1.27 1.27)
					(thickness 0.15)
				)
			)
		)
		(property "Author" "Antmicro"
			(at 0 0 0)
			(layer "F.Fab")
			(hide yes)
			(effects
				(font
					(size 1 1)
					(thickness 0.15)
				)
			)
		)
		(property "Dielectric" ""
			(at 0 0 0)
			(layer "F.Fab")
			(hide yes)
			(effects
				(font
					(size 1 1)
					(thickness 0.15)
				)
			)
		)
		(property "License" "Apache-2.0"
			(at 0 0 0)
			(layer "F.Fab")
			(hide yes)
			(effects
				(font
					(size 1 1)
					(thickness 0.15)
				)
			)
		)
		(property "MPN" "T520B337M006ATE040"
			(at 0 0 0)
			(layer "F.Fab")
			(hide yes)
			(effects
				(font
					(size 1 1)
					(thickness 0.15)
				)
			)
		)
		(property "Manufacturer" "KEMET"
			(at 0 0 0)
			(layer "F.Fab")
			(hide yes)
			(effects
				(font
					(size 1 1)
					(thickness 0.15)
				)
			)
		)
		(property "Val" "330u"
			(at 0 0 0)
			(layer "F.Fab")
			(hide yes)
			(effects
				(font
					(size 1 1)
					(thickness 0.15)
				)
			)
		)
		(property "Voltage" "6.3V"
			(at 0 0 0)
			(layer "F.Fab")
			(hide yes)
			(effects
				(font
					(size 1 1)
					(thickness 0.15)
				)
			)
		)
		(sheetname "FPGA supply")
		(sheetfile "fpga-supply.kicad_sch")
		(attr smd)
		(fp_line
			(start -2.521 -1.676)
			(end -2.123 -1.676)
			(stroke
				(width 0.15)
				(type solid)
			)
			(layer "F.SilkS")
		)
		(fp_line
			(start -2.325 -1.475)
			(end -2.325 -1.878)
			(stroke
				(width 0.15)
				(type solid)
			)
			(layer "F.SilkS")
		)
		(fp_line
			(start -1.8 -1.6)
			(end 1.8 -1.6)
			(stroke
				(width 0.15)
				(type solid)
			)
			(layer "F.SilkS")
		)
		(fp_line
			(start -1.8 -1.3)
			(end -1.8 -1.6)
			(stroke
				(width 0.15)
				(type solid)
			)
			(layer "F.SilkS")
		)
		(fp_line
			(start -1.8 1.3)
			(end -1.8 1.6)
			(stroke
				(width 0.15)
				(type solid)
			)
			(layer "F.SilkS")
		)
		(fp_line
			(start 1.8 -1.3)
			(end 1.8 -1.6)
			(stroke
				(width 0.15)
				(type solid)
			)
			(layer "F.SilkS")
		)
		(fp_line
			(start 1.8 1.3)
			(end 1.8 1.6)
			(stroke
				(width 0.15)
				(type solid)
			)
			(layer "F.SilkS")
		)
		(fp_line
			(start 1.8 1.6)
			(end -1.8 1.6)
			(stroke
				(width 0.15)
				(type solid)
			)
			(layer "F.SilkS")
		)
		(fp_line
			(start -2.411 -1.35)
			(end -2.41 1.35)
			(stroke
				(width 0.05)
				(type solid)
			)
			(layer "F.CrtYd")
		)
		(fp_line
			(start -1.97 -1.75)
			(end -1.97 -1.35)
			(stroke
				(width 0.05)
				(type solid)
			)
			(layer "F.CrtYd")
		)
		(fp_line
			(start -1.97 -1.35)
			(end -2.41 -1.35)
			(stroke
				(width 0.05)
				(type solid)
			)
			(layer "F.CrtYd")
		)
		(fp_line
			(start -1.97 1.35)
			(end -2.41 1.35)
			(stroke
				(width 0.05)
				(type solid)
			)
			(layer "F.CrtYd")
		)
		(fp_line
			(start -1.97 1.35)
			(end -1.97 1.75)
			(stroke
				(width 0.05)
				(type solid)
			)
			(layer "F.CrtYd")
		)
		(fp_line
			(start 1.959 -1.75)
			(end -1.971 -1.75)
			(stroke
				(width 0.05)
				(type solid)
			)
			(layer "F.CrtYd")
		)
		(fp_line
			(start 1.959 -1.75)
			(end 1.959 -1.35)
			(stroke
				(width 0.05)
				(type solid)
			)
			(layer "F.CrtYd")
		)
		(fp_line
			(start 1.96 1.35)
			(end 1.96 1.75)
			(stroke
				(width 0.05)
				(type solid)
			)
			(layer "F.CrtYd")
		)
		(fp_line
			(start 1.96 1.75)
			(end -1.97 1.75)
			(stroke
				(width 0.05)
				(type solid)
			)
			(layer "F.CrtYd")
		)
		(fp_line
			(start 2.399 -1.35)
			(end 1.959 -1.35)
			(stroke
				(width 0.05)
				(type solid)
			)
			(layer "F.CrtYd")
		)
		(fp_line
			(start 2.399 -1.35)
			(end 2.4 1.35)
			(stroke
				(width 0.05)
				(type solid)
			)
			(layer "F.CrtYd")
		)
		(fp_line
			(start 2.4 1.35)
			(end 1.96 1.35)
			(stroke
				(width 0.05)
				(type solid)
			)
			(layer "F.CrtYd")
		)
		(fp_line
			(start -1.7 1.324)
			(end -1.551 1.475)
			(stroke
				(width 0.15)
				(type solid)
			)
			(layer "F.Fab")
		)
		(fp_rect
			(start -1.72 -1.5)
			(end 1.719 1.499)
			(stroke
				(width 0.15)
				(type solid)
			)
			(fill no)
			(layer "F.Fab")
		)
		(pad "1" smd roundrect
			(at -1.551 0)
			(size 1.2 2.2)
			(layers "F.Cu" "F.Mask" "F.Paste")
			(roundrect_rratio 0.1)
			(net 650 "+1V0")
			(pintype "passive")
		)
		(pad "2" smd roundrect
			(at 1.55 0)
			(size 1.2 2.2)
			(layers "F.Cu" "F.Mask" "F.Paste")
			(roundrect_rratio 0.1)
			(net 1 "GND")
			(pintype "passive")
		)
	)
	(footprint "antmicro-footprints:C_0402_1005Metric"
		(layer "F.Cu")
		(at 195.803752 93.5615)
		(descr "Capacitor SMD 0402")
		(tags "capacitor SMD 0402")
		(property "Reference" "C288"
			(at -1.578752 -0.4115 0)
			(layer "F.SilkS")
			(effects
				(font
					(size 0.7 0.7)
					(thickness 0.15)
				)
				(justify left bottom)
			)
		)
		(property "Value" "C_100n_0402"
			(at 0 1.169 0)
			(layer "F.Fab")
			(effects
				(font
					(size 0.7 0.7)
					(thickness 0.15)
				)
				(justify left bottom)
			)
		)
		(property "Description" "SMD Multilayer Ceramic Capacitor, 0.1 µF, 50 V, 0402 [1005 Metric], ± 10%, X5R, GRM Series"
			(at 0 0 0)
			(layer "F.Fab")
			(hide yes)
			(effects
				(font
					(size 1.27 1.27)
					(thickness 0.15)
				)
			)
		)
		(property "Author" "Antmicro"
			(at 0 0 0)
			(layer "F.Fab")
			(hide yes)
			(effects
				(font
					(size 1 1)
					(thickness 0.15)
				)
			)
		)
		(property "Dielectric" "X5R"
			(at 0 0 0)
			(layer "F.Fab")
			(hide yes)
			(effects
				(font
					(size 1 1)
					(thickness 0.15)
				)
			)
		)
		(property "License" "Apache-2.0"
			(at 0 0 0)
			(layer "F.Fab")
			(hide yes)
			(effects
				(font
					(size 1 1)
					(thickness 0.15)
				)
			)
		)
		(property "MPN" "GRM155R61H104KE14D"
			(at 0 0 0)
			(layer "F.Fab")
			(hide yes)
			(effects
				(font
					(size 1 1)
					(thickness 0.15)
				)
			)
		)
		(property "Manufacturer" "Murata"
			(at 0 0 0)
			(layer "F.Fab")
			(hide yes)
			(effects
				(font
					(size 1 1)
					(thickness 0.15)
				)
			)
		)
		(property "Val" "100n"
			(at 0 0 0)
			(layer "F.Fab")
			(hide yes)
			(effects
				(font
					(size 1 1)
					(thickness 0.15)
				)
			)
		)
		(property "Voltage" "50V"
			(at 0 0 0)
			(layer "F.Fab")
			(hide yes)
			(effects
				(font
					(size 1 1)
					(thickness 0.15)
				)
			)
		)
		(sheetname "HDMI + Ethernet")
		(sheetfile "hdmi-ethernet.kicad_sch")
		(attr smd)
		(fp_rect
			(start -0.925 -0.47)
			(end 0.925 0.47)
			(stroke
				(width 0.05)
				(type default)
			)
			(fill no)
			(layer "F.CrtYd")
		)
		(fp_line
			(start -0.494 -0.25)
			(end 0.504 -0.25)
			(stroke
				(width 0.15)
				(type solid)
			)
			(layer "F.Fab")
		)
		(fp_line
			(start -0.494 0.248)
			(end -0.494 -0.25)
			(stroke
				(width 0.15)
				(type solid)
			)
			(layer "F.Fab")
		)
		(fp_line
			(start 0.504 -0.25)
			(end 0.504 0.248)
			(stroke
				(width 0.15)
				(type solid)
			)
			(layer "F.Fab")
		)
		(fp_line
			(start 0.504 0.248)
			(end -0.494 0.248)
			(stroke
				(width 0.15)
				(type solid)
			)
			(layer "F.Fab")
		)
		(pad "1" smd roundrect
			(at -0.48 0)
			(size 0.59 0.64)
			(layers "F.Cu" "F.Mask" "F.Paste")
			(roundrect_rratio 0.25)
			(net 1 "GND")
			(pintype "passive")
		)
		(pad "2" smd roundrect
			(at 0.48 0)
			(size 0.59 0.64)
			(layers "F.Cu" "F.Mask" "F.Paste")
			(roundrect_rratio 0.25)
			(net 727 "+1V2")
			(pintype "passive")
		)
	)
	(footprint "antmicro-footprints:Resonator_SMD_Abracon_ABM8G_3.2x2.5mm"
		(layer "F.Cu")
		(at 259.5075 138.985)
		(property "Reference" "Y2"
			(at 0.6425 2.415 180)
			(layer "F.SilkS")
			(effects
				(font
					(size 0.7 0.7)
					(thickness 0.15)
				)
				(justify left bottom)
			)
		)
		(property "Value" "Resonator_12MHz_ABM8G"
			(at -1.75 2.548 0)
			(layer "F.Fab")
			(effects
				(font
					(size 0.7 0.7)
					(thickness 0.15)
				)
				(justify left bottom)
			)
		)
		(property "Description" "Crystal, 12 MHz, SMT, 3.2mm x 2.5mm, 30 ppm, 18 pF, 20 ppm, ABM8G"
			(at 0 0 0)
			(layer "F.Fab")
			(hide yes)
			(effects
				(font
					(size 1.27 1.27)
					(thickness 0.15)
				)
			)
		)
		(property "Author" "Antmicro"
			(at 0 0 0)
			(layer "F.Fab")
			(hide yes)
			(effects
				(font
					(size 1 1)
					(thickness 0.15)
				)
			)
		)
		(property "License" "Apache-2.0"
			(at 0 0 0)
			(layer "F.Fab")
			(hide yes)
			(effects
				(font
					(size 1 1)
					(thickness 0.15)
				)
			)
		)
		(property "MPN" "ABM8G-12.000MHZ-18-D2Y-T"
			(at 0 0 0)
			(layer "F.Fab")
			(hide yes)
			(effects
				(font
					(size 1 1)
					(thickness 0.15)
				)
			)
		)
		(property "Manufacturer" "Abracon"
			(at 0 0 0)
			(layer "F.Fab")
			(hide yes)
			(effects
				(font
					(size 1 1)
					(thickness 0.15)
				)
			)
		)
		(property "Val" "12 MHz"
			(at 0 0 0)
			(layer "F.Fab")
			(hide yes)
			(effects
				(font
					(size 1 1)
					(thickness 0.15)
				)
			)
		)
		(sheetname "USB PHY")
		(sheetfile "usb-phy.kicad_sch")
		(attr smd)
		(fp_line
			(start -1.6 0.3)
			(end -1.6 -0.2)
			(stroke
				(width 0.15)
				(type solid)
			)
			(layer "F.SilkS")
		)
		(fp_line
			(start -0.35 -1.25)
			(end 0.45 -1.25)
			(stroke
				(width 0.15)
				(type solid)
			)
			(layer "F.SilkS")
		)
		(fp_line
			(start -0.35 1.25)
			(end 0.45 1.25)
			(stroke
				(width 0.15)
				(type solid)
			)
			(layer "F.SilkS")
		)
		(fp_line
			(start 1.6 0.3)
			(end 1.6 -0.2)
			(stroke
				(width 0.15)
				(type solid)
			)
			(layer "F.SilkS")
		)
		(fp_circle
			(center -1.75 1.5)
			(end -1.7 1.5)
			(stroke
				(width 0.15)
				(type solid)
			)
			(fill no)
			(layer "F.SilkS")
		)
		(fp_rect
			(start -1.907 -1.55)
			(end 2.006 1.649)
			(stroke
				(width 0.05)
				(type solid)
			)
			(fill no)
			(layer "F.CrtYd")
		)
		(pad "1" smd roundrect
			(at -1.101 0.949)
			(size 1.3 1.1)
			(layers "F.Cu" "F.Mask" "F.Paste")
			(roundrect_rratio 0)
			(chamfer_ratio 0.2)
			(chamfer bottom_left)
			(net 710 "/USB PHY/FTDI_XI")
			(pintype "passive")
		)
		(pad "2" smd rect
			(at 1.199 0.949)
			(size 1.3 1.1)
			(layers "F.Cu" "F.Mask" "F.Paste")
			(net 1 "GND")
			(pinfunction "SH")
			(pintype "passive")
		)
		(pad "3" smd rect
			(at 1.199 -0.85)
			(size 1.3 1.1)
			(layers "F.Cu" "F.Mask" "F.Paste")
			(net 713 "/USB PHY/FTDI_XO")
			(pintype "passive")
		)
		(pad "4" smd rect
			(at -1.101 -0.85)
			(size 1.3 1.1)
			(layers "F.Cu" "F.Mask" "F.Paste")
			(net 1 "GND")
			(pinfunction "SH")
			(pintype "passive")
		)
	)
	(footprint "antmicro-footprints:C_0402_1005Metric"
		(layer "F.Cu")
		(at 231.8 130.3 180)
		(descr "Capacitor SMD 0402")
		(tags "capacitor SMD 0402")
		(property "Reference" "C216"
			(at 0.9 -0.35 0)
			(layer "F.SilkS")
			(effects
				(font
					(size 0.7 0.7)
					(thickness 0.15)
				)
				(justify right bottom)
			)
		)
		(property "Value" "C_1u_0402"
			(at 0 1.4 0)
			(layer "F.Fab")
			(effects
				(font
					(size 0.7 0.7)
					(thickness 0.15)
				)
				(justify right bottom)
			)
		)
		(property "Description" "SMD Multilayer Ceramic Capacitor, 1 µF, 10 V, 0402 [1005 Metric], ± 10%, X6S, C"
			(at 0 0 180)
			(layer "F.Fab")
			(hide yes)
			(effects
				(font
					(size 1.27 1.27)
					(thickness 0.15)
				)
			)
		)
		(property "Author" "Antmicro"
			(at 463.6 260.6 0)
			(layer "F.Fab")
			(hide yes)
			(effects
				(font
					(size 1 1)
					(thickness 0.15)
				)
			)
		)
		(property "Dielectric" ""
			(at 463.6 260.6 0)
			(layer "F.Fab")
			(hide yes)
			(effects
				(font
					(size 1 1)
					(thickness 0.15)
				)
			)
		)
		(property "License" "Apache-2.0"
			(at 463.6 260.6 0)
			(layer "F.Fab")
			(hide yes)
			(effects
				(font
					(size 1 1)
					(thickness 0.15)
				)
			)
		)
		(property "MPN" "C1005X6S1A105K050BC"
			(at 463.6 260.6 0)
			(layer "F.Fab")
			(hide yes)
			(effects
				(font
					(size 1 1)
					(thickness 0.15)
				)
			)
		)
		(property "Manufacturer" "TDK"
			(at 463.6 260.6 0)
			(layer "F.Fab")
			(hide yes)
			(effects
				(font
					(size 1 1)
					(thickness 0.15)
				)
			)
		)
		(property "Val" "1u"
			(at 463.6 260.6 0)
			(layer "F.Fab")
			(hide yes)
			(effects
				(font
					(size 1 1)
					(thickness 0.15)
				)
			)
		)
		(property "Voltage" ""
			(at 463.6 260.6 0)
			(layer "F.Fab")
			(hide yes)
			(effects
				(font
					(size 1 1)
					(thickness 0.15)
				)
			)
		)
		(sheetname "User GPIO + LED + button + DIP switch")
		(sheetfile "user-gpio.kicad_sch")
		(attr smd)
		(fp_rect
			(start -0.925 -0.47)
			(end 0.925 0.47)
			(stroke
				(width 0.05)
				(type default)
			)
			(fill no)
			(layer "F.CrtYd")
		)
		(fp_line
			(start 0.504 0.248)
			(end -0.494 0.248)
			(stroke
				(width 0.15)
				(type solid)
			)
			(layer "F.Fab")
		)
		(fp_line
			(start 0.504 -0.25)
			(end 0.504 0.248)
			(stroke
				(width 0.15)
				(type solid)
			)
			(layer "F.Fab")
		)
		(fp_line
			(start -0.494 0.248)
			(end -0.494 -0.25)
			(stroke
				(width 0.15)
				(type solid)
			)
			(layer "F.Fab")
		)
		(fp_line
			(start -0.494 -0.25)
			(end 0.504 -0.25)
			(stroke
				(width 0.15)
				(type solid)
			)
			(layer "F.Fab")
		)
		(pad "1" smd roundrect
			(at -0.48 0 180)
			(size 0.59 0.64)
			(layers "F.Cu" "F.Mask" "F.Paste")
			(roundrect_rratio 0.25)
			(net 1 "GND")
			(pintype "passive")
		)
		(pad "2" smd roundrect
			(at 0.48 0 180)
			(size 0.59 0.64)
			(layers "F.Cu" "F.Mask" "F.Paste")
			(roundrect_rratio 0.25)
			(net 703 "+5V")
			(pintype "passive")
		)
	)
	(footprint "antmicro-footprints:NetTie-2_SMD_Pad0.127mm"
		(layer "F.Cu")
		(at 240 124.727 -90)
		(descr "Net tie, 2 pin, 0.127mm  SMD pads")
		(tags "net tie")
		(property "Reference" "NT16"
			(at -0.128 -1.345 270)
			(layer "F.SilkS")
			(hide yes)
			(effects
				(font
					(size 0.7 0.7)
					(thickness 0.15)
				)
				(justify left bottom)
			)
		)
		(property "Value" "Net-Tie_2"
			(at 0 1.199 270)
			(layer "F.Fab")
			(effects
				(font
					(size 0.7 0.7)
					(thickness 0.15)
				)
				(justify left bottom)
			)
		)
		(property "Description" "Net tie, 2 pins"
			(at 0 0 270)
			(layer "F.Fab")
			(hide yes)
			(effects
				(font
					(size 1.27 1.27)
					(thickness 0.15)
				)
			)
		)
		(property "Author" "Antmicro"
			(at 115.273 364.727 0)
			(layer "F.Fab")
			(hide yes)
			(effects
				(font
					(size 1 1)
					(thickness 0.15)
				)
			)
		)
		(property "License" "Apache-2.0"
			(at 115.273 364.727 0)
			(layer "F.Fab")
			(hide yes)
			(effects
				(font
					(size 1 1)
					(thickness 0.15)
				)
			)
		)
		(property "MPN" ""
			(at 115.273 364.727 0)
			(layer "F.Fab")
			(hide yes)
			(effects
				(font
					(size 1 1)
					(thickness 0.15)
				)
			)
		)
		(property "Manufacturer" ""
			(at 115.273 364.727 0)
			(layer "F.Fab")
			(hide yes)
			(effects
				(font
					(size 1 1)
					(thickness 0.15)
				)
			)
		)
		(sheetname "FPGA Bank 12 & 13")
		(sheetfile "fpga-bank-12-13.kicad_sch")
		(attr exclude_from_pos_files)
		(net_tie_pad_groups "1, 2")
		(fp_poly
			(pts
				(xy -0.0635 -0.0635) (xy 0.0625 -0.0635) (xy 0.0625 0.0635) (xy -0.0635 0.0635)
			)
			(stroke
				(width 0)
				(type solid)
			)
			(fill yes)
			(layer "F.Cu")
		)
		(pad "1" smd roundrect
			(at -0.127 0 90)
			(size 0.127 0.127)
			(layers "F.Cu")
			(roundrect_rratio 0.5)
			(chamfer_ratio 0)
			(chamfer top_left bottom_left)
			(net 1329 "/SUP_MCU.TX0")
			(pinfunction "1")
			(pintype "passive")
		)
		(pad "2" smd roundrect
			(at 0.126 0 270)
			(size 0.127 0.127)
			(layers "F.Cu")
			(roundrect_rratio 0.5)
			(chamfer_ratio 0)
			(chamfer top_left bottom_left)
			(net 46 "/FPGA Bank 12 & 13/UART0.RX")
			(pinfunction "2")
			(pintype "passive")
		)
	)
)
